(kicad_pcb
	(version 20260206)
	(generator "pcbnew")
	(generator_version "10.0")
	(general
		(thickness 1.6)
		(legacy_teardrops no)
	)
	(paper "A4")
	(title_block
		(title "v2-pdb — ms_pdb_v2.brd")
		(comment 1 "Open CloudServer (Microsoft) / footprints 8-14 of 348")
	)
	(layers
		(0 "F.Cu" signal "TOP")
		(4 "In1.Cu" signal "GND")
		(6 "In2.Cu" signal "IN1")
		(8 "In3.Cu" signal "VCC")
		(10 "In4.Cu" signal "VCC1")
		(12 "In5.Cu" signal "IN2")
		(14 "In6.Cu" signal "GND1")
		(2 "B.Cu" signal "BOTTOM")
		(9 "F.Adhes" user "F.Adhesive")
		(11 "B.Adhes" user "B.Adhesive")
		(13 "F.Paste" user "Package Geometry/Pastemask Top")
		(15 "B.Paste" user "Package Geometry/Pastemask Bottom")
		(5 "F.SilkS" user "Ref Des/Silkscreen Top")
		(7 "B.SilkS" user "Ref Des/Silkscreen Bottom")
		(1 "F.Mask" user "Board Geometry/Soldermask Top")
		(3 "B.Mask" user "Board Geometry/Soldermask Bottom")
		(17 "Dwgs.User" user "User.Drawings")
		(19 "Cmts.User" user "User.Comments")
		(21 "Eco1.User" user "User.Eco1")
		(23 "Eco2.User" user "User.Eco2")
		(25 "Edge.Cuts" user "Board Geometry/Outline")
		(27 "Margin" user)
		(31 "F.CrtYd" user "Package Geometry/Place Bound Top")
		(29 "B.CrtYd" user "Package Geometry/Place Bound Bottom")
		(35 "F.Fab" user "Ref Des/Assembly Top")
		(33 "B.Fab" user "Ref Des/Assembly Bottom")
	)
	(footprint ""
		(layer "F.Cu")
		(at 25.857708 -364.246414)
		(property "Reference" "R78"
			(at -3.917442 -0.225298 0)
			(unlocked yes)
			(layer "F.SilkS")
			(effects
				(font
					(size 0.7874 0.5842)
					(thickness 0.1524)
				)
				(justify left)
			)
		)
		(property "Value" ""
			(at 0 0 0)
			(layer "F.Fab")
			(effects
				(font
					(size 1.27 1.27)
				)
			)
		)
		(duplicate_pad_numbers_are_jumpers no)
		(fp_line
			(start -0.7874 -0.4064)
			(end 0.7874 -0.4064)
			(stroke
				(width 0.1524)
				(type default)
			)
			(layer "F.SilkS")
		)
		(fp_line
			(start -0.7874 0.4064)
			(end -0.7874 -0.4064)
			(stroke
				(width 0.1524)
				(type default)
			)
			(layer "F.SilkS")
		)
		(fp_line
			(start 0.7874 -0.4064)
			(end 0.7874 0.4064)
			(stroke
				(width 0.1524)
				(type default)
			)
			(layer "F.SilkS")
		)
		(fp_line
			(start 0.7874 0.4064)
			(end -0.7874 0.4064)
			(stroke
				(width 0.1524)
				(type default)
			)
			(layer "F.SilkS")
		)
		(fp_poly
			(pts
				(xy -0.508 0.2794) (xy -0.508 0.2286) (xy -0.635 0.2286) (xy -0.635 -0.254) (xy -0.5334 -0.254)
				(xy -0.5334 -0.2794) (xy 0.5334 -0.2794) (xy 0.5334 -0.254) (xy 0.635 -0.254) (xy 0.635 0.254) (xy 0.5334 0.254)
				(xy 0.5334 0.2794)
			)
			(stroke
				(width 0)
				(type default)
			)
			(fill no)
			(layer "F.CrtYd")
		)
		(pad "1" smd rect
			(at 0.40005 0)
			(size 0.4572 0.508)
			(layers "F.Cu" "F.Mask" "F.Paste")
			(net "PSU5_PS_KILL")
		)
		(pad "2" smd rect
			(at -0.40005 0)
			(size 0.4572 0.508)
			(layers "F.Cu" "F.Mask" "F.Paste")
			(net "P12V_STBY")
		)
	)
	(footprint ""
		(layer "F.Cu")
		(at 5.780024 -497.999766)
		(property "Reference" "J31"
			(at -1.9304 -3.978148 0)
			(unlocked yes)
			(layer "F.SilkS")
			(effects
				(font
					(size 0.7874 0.5842)
					(thickness 0.1524)
				)
				(justify left)
			)
		)
		(property "Value" ""
			(at 0 0 0)
			(layer "F.Fab")
			(effects
				(font
					(size 1.27 1.27)
				)
			)
		)
		(duplicate_pad_numbers_are_jumpers no)
		(fp_line
			(start -3.10007 0.199898)
			(end -3.10007 2.800096)
			(stroke
				(width 0.1524)
				(type default)
			)
			(layer "F.SilkS")
		)
		(fp_line
			(start -3.10007 2.800096)
			(end -1.89992 2.800096)
			(stroke
				(width 0.1524)
				(type default)
			)
			(layer "F.SilkS")
		)
		(fp_line
			(start -1.89992 -3.325114)
			(end -1.89992 0.199898)
			(stroke
				(width 0.1524)
				(type default)
			)
			(layer "F.SilkS")
		)
		(fp_line
			(start -1.89992 0.199898)
			(end -3.10007 0.199898)
			(stroke
				(width 0.1524)
				(type default)
			)
			(layer "F.SilkS")
		)
		(fp_line
			(start -1.89992 2.800096)
			(end -1.89992 6.325108)
			(stroke
				(width 0.1524)
				(type default)
			)
			(layer "F.SilkS")
		)
		(fp_line
			(start -1.89992 6.325108)
			(end 1.016 6.325108)
			(stroke
				(width 0.1524)
				(type default)
			)
			(layer "F.SilkS")
		)
		(fp_line
			(start 1.016 -3.325114)
			(end -1.89992 -3.325114)
			(stroke
				(width 0.1524)
				(type default)
			)
			(layer "F.SilkS")
		)
		(fp_line
			(start 2.469896 5.133594)
			(end 2.469896 -2.130806)
			(stroke
				(width 0.1524)
				(type default)
			)
			(layer "F.SilkS")
		)
		(fp_poly
			(pts
				(xy 0.8509 0.8509) (xy -0.8509 0.8509) (xy -0.8509 -0.8509) (xy 0.8509 -0.8509)
			)
			(stroke
				(width 0)
				(type default)
			)
			(fill no)
			(layer "B.CrtYd")
		)
		(fp_poly
			(pts
				(arc
					(start 0.8509 2.999994)
					(mid -0.8509 2.999994)
					(end 0.8509 2.999994)
				)
			)
			(stroke
				(width 0)
				(type default)
			)
			(fill no)
			(layer "B.CrtYd")
		)
		(fp_poly
			(pts
				(arc
					(start 2.874518 -2.999994)
					(mid 1.045718 -2.999994)
					(end 2.874518 -2.999994)
				)
			)
			(stroke
				(width 0)
				(type default)
			)
			(fill no)
			(layer "B.CrtYd")
		)
		(fp_poly
			(pts
				(arc
					(start 2.874518 5.999988)
					(mid 1.045718 5.999988)
					(end 2.874518 5.999988)
				)
			)
			(stroke
				(width 0)
				(type default)
			)
			(fill no)
			(layer "B.CrtYd")
		)
		(fp_poly
			(pts
				(xy 2.469896 5.233924) (xy 2.469896 -2.233676) (xy 2.8956 -2.233676) (xy 2.8956 -3.935476) (xy 1.0922 -3.935476)
				(xy 1.0922 -3.325114) (xy -1.89992 -3.325114) (xy -1.89992 0.199898) (xy -3.10007 0.199898) (xy -3.10007 2.800096)
				(xy -1.89992 2.800096) (xy -1.89992 6.325108) (xy 1.0922 6.325108) (xy 1.0922 6.935724) (xy 2.8956 6.935724)
				(xy 2.8956 5.233924)
			)
			(stroke
				(width 0)
				(type default)
			)
			(fill no)
			(layer "F.CrtYd")
		)
		(fp_line
			(start -3.10007 0.199898)
			(end -3.10007 2.800096)
			(stroke
				(width 0.1)
				(type default)
			)
			(layer "F.Fab")
		)
		(fp_line
			(start -3.10007 2.800096)
			(end -1.89992 2.800096)
			(stroke
				(width 0.1)
				(type default)
			)
			(layer "F.Fab")
		)
		(fp_line
			(start -1.89992 -3.325114)
			(end -1.89992 0.199898)
			(stroke
				(width 0.1)
				(type default)
			)
			(layer "F.Fab")
		)
		(fp_line
			(start -1.89992 0.199898)
			(end -3.10007 0.199898)
			(stroke
				(width 0.1)
				(type default)
			)
			(layer "F.Fab")
		)
		(fp_line
			(start -1.89992 2.800096)
			(end -1.89992 6.325108)
			(stroke
				(width 0.1)
				(type default)
			)
			(layer "F.Fab")
		)
		(fp_line
			(start -1.89992 6.325108)
			(end 2.469896 6.325108)
			(stroke
				(width 0.1)
				(type default)
			)
			(layer "F.Fab")
		)
		(fp_line
			(start 2.469896 -3.325114)
			(end -1.89992 -3.325114)
			(stroke
				(width 0.1)
				(type default)
			)
			(layer "F.Fab")
		)
		(fp_line
			(start 2.469896 6.325108)
			(end 2.469896 -3.325114)
			(stroke
				(width 0.1)
				(type default)
			)
			(layer "F.Fab")
		)
		(pad "" np_thru_hole circle
			(at 1.960118 -2.999994 90)
			(size 1.3208 1.3208)
			(drill 1.3208)
			(layers "*.Cu" "*.Mask")
			(clearance 0.381)
			(thermal_gap 0.381)
		)
		(pad "" np_thru_hole circle
			(at 1.960118 5.999988 90)
			(size 1.3208 1.3208)
			(drill 1.3208)
			(layers "*.Cu" "*.Mask")
			(clearance 0.381)
			(thermal_gap 0.381)
		)
		(pad "1" thru_hole rect
			(at 0 0 90)
			(size 1.6002 1.6002)
			(drill 1.0922)
			(layers "*.Cu" "*.Mask")
			(remove_unused_layers no)
			(net "POWER_SW2_PWR_CTR_12V")
			(clearance 0)
			(padstack
				(mode front_inner_back)
				(layer "Inner"
					(shape circle)
					(size 1.6002 1.6002)
					(clearance 0)
				)
				(layer "B.Cu"
					(shape rect)
					(size 1.6002 1.6002)
					(clearance 0)
				)
			)
		)
		(pad "2" thru_hole circle
			(at 0 2.999994 90)
			(size 1.6002 1.6002)
			(drill 1.0922)
			(layers "*.Cu" "*.Mask")
			(remove_unused_layers no)
			(net "GND")
			(clearance 0)
		)
		(zone
			(layers "F.Cu" "B.Cu" "In1.Cu" "In2.Cu" "In3.Cu" "In4.Cu" "In5.Cu" "In6.Cu")
			(hatch none 0.5)
			(connect_pads
				(clearance 0)
			)
			(min_thickness 0.25)
			(keepout
				(tracks not_allowed)
				(vias allowed)
				(pads allowed)
				(copperpour not_allowed)
				(footprints allowed)
			)
			(placement
				(enabled no)
				(sheetname "")
			)
			(fill
				(thermal_gap 0.5)
				(thermal_bridge_width 0.5)
				(island_removal_mode 0)
			)
			(polygon
				(pts
					(arc
						(start 8.806942 -500.99976)
						(mid 6.673342 -500.99976)
						(end 8.806942 -500.99976)
					)
				)
			)
		)
		(zone
			(layers "F.Cu" "B.Cu" "In1.Cu" "In2.Cu" "In3.Cu" "In4.Cu" "In5.Cu" "In6.Cu")
			(hatch none 0.5)
			(connect_pads
				(clearance 0)
			)
			(min_thickness 0.25)
			(keepout
				(tracks not_allowed)
				(vias allowed)
				(pads allowed)
				(copperpour not_allowed)
				(footprints allowed)
			)
			(placement
				(enabled no)
				(sheetname "")
			)
			(fill
				(thermal_gap 0.5)
				(thermal_bridge_width 0.5)
				(island_removal_mode 0)
			)
			(polygon
				(pts
					(arc
						(start 8.806942 -491.999778)
						(mid 6.673342 -491.999778)
						(end 8.806942 -491.999778)
					)
				)
			)
		)
	)
	(footprint ""
		(layer "F.Cu")
		(at 70.308978 -304.009806 90)
		(property "Reference" "C53"
			(at 1.017524 0.29464 90)
			(unlocked yes)
			(layer "F.SilkS")
			(effects
				(font
					(size 0.7874 0.5842)
					(thickness 0.1524)
				)
				(justify left)
			)
		)
		(property "Value" ""
			(at 0 0 90)
			(layer "F.Fab")
			(effects
				(font
					(size 1.27 1.27)
				)
			)
		)
		(duplicate_pad_numbers_are_jumpers no)
		(fp_line
			(start 0.7874 -0.4064)
			(end 0.7874 0.4064)
			(stroke
				(width 0.1524)
				(type default)
			)
			(layer "F.SilkS")
		)
		(fp_line
			(start -0.7874 -0.4064)
			(end 0.7874 -0.4064)
			(stroke
				(width 0.1524)
				(type default)
			)
			(layer "F.SilkS")
		)
		(fp_line
			(start 0 0.381)
			(end 0 -0.381)
			(stroke
				(width 0.1524)
				(type default)
			)
			(layer "F.SilkS")
		)
		(fp_line
			(start 0.7874 0.4064)
			(end -0.7874 0.4064)
			(stroke
				(width 0.1524)
				(type default)
			)
			(layer "F.SilkS")
		)
		(fp_line
			(start -0.7874 0.4064)
			(end -0.7874 -0.4064)
			(stroke
				(width 0.1524)
				(type default)
			)
			(layer "F.SilkS")
		)
		(fp_poly
			(pts
				(xy -0.5334 0.254) (xy -0.635 0.254) (xy -0.635 0.2286) (xy -0.635 -0.254) (xy -0.5334 -0.254) (xy -0.5334 -0.2794)
				(xy 0.5334 -0.2794) (xy 0.5334 -0.254) (xy 0.635 -0.254) (xy 0.635 0.254) (xy 0.5334 0.254) (xy 0.5334 0.2794)
				(xy -0.508 0.2794) (xy -0.5334 0.2794)
			)
			(stroke
				(width 0)
				(type default)
			)
			(fill no)
			(layer "F.CrtYd")
		)
		(pad "1" smd rect
			(at 0.40005 0 90)
			(size 0.4572 0.508)
			(layers "F.Cu" "F.Mask" "F.Paste")
			(net "P12V")
		)
		(pad "2" smd rect
			(at -0.40005 0 90)
			(size 0.4572 0.508)
			(layers "F.Cu" "F.Mask" "F.Paste")
			(net "GND")
		)
	)
	(footprint ""
		(layer "F.Cu")
		(at 26.102056 -274.774914)
		(property "Reference" "R74"
			(at -4.037838 -0.005334 0)
			(unlocked yes)
			(layer "F.SilkS")
			(effects
				(font
					(size 0.7874 0.5842)
					(thickness 0.1524)
				)
				(justify left)
			)
		)
		(property "Value" ""
			(at 0 0 0)
			(layer "F.Fab")
			(effects
				(font
					(size 1.27 1.27)
				)
			)
		)
		(duplicate_pad_numbers_are_jumpers no)
		(fp_line
			(start -0.7874 -0.4064)
			(end 0.7874 -0.4064)
			(stroke
				(width 0.1524)
				(type default)
			)
			(layer "F.SilkS")
		)
		(fp_line
			(start -0.7874 0.4064)
			(end -0.7874 -0.4064)
			(stroke
				(width 0.1524)
				(type default)
			)
			(layer "F.SilkS")
		)
		(fp_line
			(start 0.7874 -0.4064)
			(end 0.7874 0.4064)
			(stroke
				(width 0.1524)
				(type default)
			)
			(layer "F.SilkS")
		)
		(fp_line
			(start 0.7874 0.4064)
			(end -0.7874 0.4064)
			(stroke
				(width 0.1524)
				(type default)
			)
			(layer "F.SilkS")
		)
		(fp_poly
			(pts
				(xy -0.508 0.2794) (xy -0.508 0.2286) (xy -0.635 0.2286) (xy -0.635 -0.254) (xy -0.5334 -0.254)
				(xy -0.5334 -0.2794) (xy 0.5334 -0.2794) (xy 0.5334 -0.254) (xy 0.635 -0.254) (xy 0.635 0.254) (xy 0.5334 0.254)
				(xy 0.5334 0.2794)
			)
			(stroke
				(width 0)
				(type default)
			)
			(fill no)
			(layer "F.CrtYd")
		)
		(pad "1" smd rect
			(at 0.40005 0)
			(size 0.4572 0.508)
			(layers "F.Cu" "F.Mask" "F.Paste")
			(net "PSU4_PS_KILL")
		)
		(pad "2" smd rect
			(at -0.40005 0)
			(size 0.4572 0.508)
			(layers "F.Cu" "F.Mask" "F.Paste")
			(net "P12V_STBY")
		)
	)
	(footprint ""
		(layer "F.Cu")
		(at 26.850848 -19.859244)
		(property "Reference" "R5"
			(at -2.617978 0.04699 0)
			(unlocked yes)
			(layer "F.SilkS")
			(effects
				(font
					(size 0.7874 0.5842)
					(thickness 0.1524)
				)
				(justify left)
			)
		)
		(property "Value" ""
			(at 0 0 0)
			(layer "F.Fab")
			(effects
				(font
					(size 1.27 1.27)
				)
			)
		)
		(duplicate_pad_numbers_are_jumpers no)
		(fp_line
			(start -0.7874 -0.4064)
			(end 0.7874 -0.4064)
			(stroke
				(width 0.1524)
				(type default)
			)
			(layer "F.SilkS")
		)
		(fp_line
			(start -0.7874 0.4064)
			(end -0.7874 -0.4064)
			(stroke
				(width 0.1524)
				(type default)
			)
			(layer "F.SilkS")
		)
		(fp_line
			(start 0.7874 -0.4064)
			(end 0.7874 0.4064)
			(stroke
				(width 0.1524)
				(type default)
			)
			(layer "F.SilkS")
		)
		(fp_line
			(start 0.7874 0.4064)
			(end -0.7874 0.4064)
			(stroke
				(width 0.1524)
				(type default)
			)
			(layer "F.SilkS")
		)
		(fp_poly
			(pts
				(xy -0.508 0.2794) (xy -0.508 0.2286) (xy -0.635 0.2286) (xy -0.635 -0.254) (xy -0.5334 -0.254)
				(xy -0.5334 -0.2794) (xy 0.5334 -0.2794) (xy 0.5334 -0.254) (xy 0.635 -0.254) (xy 0.635 0.254) (xy 0.5334 0.254)
				(xy 0.5334 0.2794)
			)
			(stroke
				(width 0)
				(type default)
			)
			(fill no)
			(layer "F.CrtYd")
		)
		(pad "1" smd rect
			(at 0.40005 0)
			(size 0.4572 0.508)
			(layers "F.Cu" "F.Mask" "F.Paste")
			(net "PSU1_REMOTE_N")
		)
		(pad "2" smd rect
			(at -0.40005 0)
			(size 0.4572 0.508)
			(layers "F.Cu" "F.Mask" "F.Paste")
			(net "GND")
		)
	)
	(footprint ""
		(layer "F.Cu")
		(at 73.63333 -83.335368 90)
		(property "Reference" "C19"
			(at 1.06553 0.092202 90)
			(unlocked yes)
			(layer "F.SilkS")
			(effects
				(font
					(size 0.7874 0.5842)
					(thickness 0.1524)
				)
				(justify left)
			)
		)
		(property "Value" ""
			(at 0 0 90)
			(layer "F.Fab")
			(effects
				(font
					(size 1.27 1.27)
				)
			)
		)
		(duplicate_pad_numbers_are_jumpers no)
		(fp_line
			(start 0.7874 -0.4064)
			(end 0.7874 0.4064)
			(stroke
				(width 0.1524)
				(type default)
			)
			(layer "F.SilkS")
		)
		(fp_line
			(start -0.7874 -0.4064)
			(end 0.7874 -0.4064)
			(stroke
				(width 0.1524)
				(type default)
			)
			(layer "F.SilkS")
		)
		(fp_line
			(start 0 0.381)
			(end 0 -0.381)
			(stroke
				(width 0.1524)
				(type default)
			)
			(layer "F.SilkS")
		)
		(fp_line
			(start 0.7874 0.4064)
			(end -0.7874 0.4064)
			(stroke
				(width 0.1524)
				(type default)
			)
			(layer "F.SilkS")
		)
		(fp_line
			(start -0.7874 0.4064)
			(end -0.7874 -0.4064)
			(stroke
				(width 0.1524)
				(type default)
			)
			(layer "F.SilkS")
		)
		(fp_poly
			(pts
				(xy -0.5334 0.254) (xy -0.635 0.254) (xy -0.635 0.2286) (xy -0.635 -0.254) (xy -0.5334 -0.254) (xy -0.5334 -0.2794)
				(xy 0.5334 -0.2794) (xy 0.5334 -0.254) (xy 0.635 -0.254) (xy 0.635 0.254) (xy 0.5334 0.254) (xy 0.5334 0.2794)
				(xy -0.508 0.2794) (xy -0.5334 0.2794)
			)
			(stroke
				(width 0)
				(type default)
			)
			(fill no)
			(layer "F.CrtYd")
		)
		(pad "1" smd rect
			(at 0.40005 0 90)
			(size 0.4572 0.508)
			(layers "F.Cu" "F.Mask" "F.Paste")
			(net "P12V")
		)
		(pad "2" smd rect
			(at -0.40005 0 90)
			(size 0.4572 0.508)
			(layers "F.Cu" "F.Mask" "F.Paste")
			(net "GND")
		)
	)
	(footprint ""
		(layer "F.Cu")
		(at 39.94531 -459.16596 180)
		(property "Reference" "R26"
			(at -1.790446 -0.167386 0)
			(unlocked yes)
			(layer "F.SilkS")
			(effects
				(font
					(size 0.7874 0.5842)
					(thickness 0.1524)
				)
				(justify left)
			)
		)
		(property "Value" ""
			(at 0 0 180)
			(layer "F.Fab")
			(effects
				(font
					(size 1.27 1.27)
				)
			)
		)
		(duplicate_pad_numbers_are_jumpers no)
		(fp_line
			(start 0.7874 0.4064)
			(end -0.7874 0.4064)
			(stroke
				(width 0.1524)
				(type default)
			)
			(layer "F.SilkS")
		)
		(fp_line
			(start 0.7874 -0.4064)
			(end 0.7874 0.4064)
			(stroke
				(width 0.1524)
				(type default)
			)
			(layer "F.SilkS")
		)
		(fp_line
			(start -0.7874 0.4064)
			(end -0.7874 -0.4064)
			(stroke
				(width 0.1524)
				(type default)
			)
			(layer "F.SilkS")
		)
		(fp_line
			(start -0.7874 -0.4064)
			(end 0.7874 -0.4064)
			(stroke
				(width 0.1524)
				(type default)
			)
			(layer "F.SilkS")
		)
		(fp_poly
			(pts
				(xy -0.508 0.2794) (xy -0.508 0.2286) (xy -0.635 0.2286) (xy -0.635 -0.254) (xy -0.5334 -0.254)
				(xy -0.5334 -0.2794) (xy 0.5334 -0.2794) (xy 0.5334 -0.254) (xy 0.635 -0.254) (xy 0.635 0.254) (xy 0.5334 0.254)
				(xy 0.5334 0.2794)
			)
			(stroke
				(width 0)
				(type default)
			)
			(fill no)
			(layer "F.CrtYd")
		)
		(pad "1" smd rect
			(at 0.40005 0 180)
			(size 0.4572 0.508)
			(layers "F.Cu" "F.Mask" "F.Paste")
			(net "PSU6_RETURN")
		)
		(pad "2" smd rect
			(at -0.40005 0 180)
			(size 0.4572 0.508)
			(layers "F.Cu" "F.Mask" "F.Paste")
			(net "GND")
		)
	)
)
